(kicad_pcb
	(version 20241229)
	(generator "pcbnew")
	(generator_version "9.0")
	(general
		(thickness 1.292)
		(legacy_teardrops no)
	)
	(paper "A4")
	(title_block
		(title "LPDDR5 Testbed")
		(date "2023-12-19")
		(rev "1.0.0")
		(comment 9 "footprints 17-23 of 160")
	)
	(layers
		(0 "F.Cu" signal)
		(4 "In1.Cu" power)
		(6 "In2.Cu" power)
		(8 "In3.Cu" signal)
		(10 "In4.Cu" signal)
		(2 "B.Cu" signal)
		(9 "F.Adhes" user "F.Adhesive")
		(11 "B.Adhes" user "B.Adhesive")
		(13 "F.Paste" user)
		(15 "B.Paste" user)
		(5 "F.SilkS" user "F.Silkscreen")
		(7 "B.SilkS" user "B.Silkscreen")
		(1 "F.Mask" user)
		(3 "B.Mask" user)
		(17 "Dwgs.User" user "User.Drawings")
		(19 "Cmts.User" user "User.Comments")
		(21 "Eco1.User" user "User.Eco1")
		(23 "Eco2.User" user "User.Eco2")
		(25 "Edge.Cuts" user)
		(27 "Margin" user)
		(31 "F.CrtYd" user "F.Courtyard")
		(29 "B.CrtYd" user "B.Courtyard")
		(35 "F.Fab" user)
		(33 "B.Fab" user)
	)
	(footprint "antmicro-footprints:R_0603_1608Metric"
		(layer "F.Cu")
		(at 114.25 70.9 180)
		(descr "Resistor SMD 0603")
		(tags "resistor SMD 0603")
		(property "Reference" "R45"
			(at -1.45 -1.7 0)
			(unlocked yes)
			(layer "F.SilkS")
			(effects
				(font
					(size 0.7 0.7)
					(thickness 0.15)
				)
				(justify right bottom)
			)
		)
		(property "Value" "R_0R_22.4A_0603"
			(at 0 1.6 0)
			(layer "F.Fab")
			(effects
				(font
					(size 0.7 0.7)
					(thickness 0.15)
				)
				(justify right bottom)
			)
		)
		(property "Author" "Antmicro"
			(at 228.5 141.8 0)
			(layer "F.Fab")
			(hide yes)
			(effects
				(font
					(size 1 1)
					(thickness 0.15)
				)
			)
		)
		(property "License" "Apache-2.0"
			(at 228.5 141.8 0)
			(layer "F.Fab")
			(hide yes)
			(effects
				(font
					(size 1 1)
					(thickness 0.15)
				)
			)
		)
		(property "MPN" "PMR03EZPJ000"
			(at 228.5 141.8 0)
			(layer "F.Fab")
			(hide yes)
			(effects
				(font
					(size 1 1)
					(thickness 0.15)
				)
			)
		)
		(property "Manufacturer" "ROHM Semiconductor"
			(at 228.5 141.8 0)
			(layer "F.Fab")
			(hide yes)
			(effects
				(font
					(size 1 1)
					(thickness 0.15)
				)
			)
		)
		(property "Max. Curr." "22.4A"
			(at 228.5 141.8 0)
			(layer "F.Fab")
			(hide yes)
			(effects
				(font
					(size 1 1)
					(thickness 0.15)
				)
			)
		)
		(property "Tolerance" "template_tolerance"
			(at 228.5 141.8 0)
			(layer "F.Fab")
			(hide yes)
			(effects
				(font
					(size 1 1)
					(thickness 0.15)
				)
			)
		)
		(property "Val" "0R"
			(at 228.5 141.8 0)
			(layer "F.Fab")
			(hide yes)
			(effects
				(font
					(size 1 1)
					(thickness 0.15)
				)
			)
		)
		(sheetname "Power supply")
		(sheetfile "power_supply.kicad_sch")
		(attr smd)
		(fp_line
			(start -0.3 0.3)
			(end 0.3 0.3)
			(stroke
				(width 0.15)
				(type solid)
			)
			(layer "F.SilkS")
		)
		(fp_line
			(start -0.3 -0.3)
			(end 0.3 -0.3)
			(stroke
				(width 0.15)
				(type solid)
			)
			(layer "F.SilkS")
		)
		(fp_rect
			(start -1.25 -0.7)
			(end 1.25 0.7)
			(stroke
				(width 0.05)
				(type solid)
			)
			(fill no)
			(layer "F.CrtYd")
		)
		(fp_rect
			(start -0.8 -0.4)
			(end 0.8 0.4)
			(stroke
				(width 0.15)
				(type solid)
			)
			(fill no)
			(layer "F.Fab")
		)
		(pad "1" smd roundrect
			(at -0.7 0 180)
			(size 0.6 0.8)
			(layers "F.Cu" "F.Mask" "F.Paste")
			(roundrect_rratio 0.2)
			(net 13 "+1V05")
			(pintype "passive")
		)
		(pad "2" smd roundrect
			(at 0.7 0 180)
			(size 0.6 0.8)
			(layers "F.Cu" "F.Mask" "F.Paste")
			(roundrect_rratio 0.2)
			(net 9 "/Power supply/VOUT3")
			(pintype "passive")
		)
	)
	(footprint "antmicro-footprints:R_0402_1005Metric"
		(layer "F.Cu")
		(at 162.075 65.35)
		(descr "Resistor SMD 0402")
		(tags "resistor SMD 0402")
		(property "Reference" "R29"
			(at -7.175 0.65 0)
			(unlocked yes)
			(layer "F.SilkS")
			(effects
				(font
					(size 0.7 0.7)
					(thickness 0.15)
				)
				(justify left bottom)
			)
		)
		(property "Value" "R_0R_0402"
			(at -1.011843 1.772047 0)
			(layer "F.Fab")
			(effects
				(font
					(size 0.7 0.7)
					(thickness 0.15)
				)
				(justify left bottom)
			)
		)
		(property "Author" "Antmicro"
			(at 0 0 0)
			(layer "F.Fab")
			(hide yes)
			(effects
				(font
					(size 1 1)
					(thickness 0.15)
				)
			)
		)
		(property "Current" "1A"
			(at 0 0 0)
			(layer "F.Fab")
			(hide yes)
			(effects
				(font
					(size 1 1)
					(thickness 0.15)
				)
			)
		)
		(property "License" "Apache-2.0"
			(at 0 0 0)
			(layer "F.Fab")
			(hide yes)
			(effects
				(font
					(size 1 1)
					(thickness 0.15)
				)
			)
		)
		(property "MPN" "ERJ2GE0R00X"
			(at 0 0 0)
			(layer "F.Fab")
			(hide yes)
			(effects
				(font
					(size 1 1)
					(thickness 0.15)
				)
			)
		)
		(property "Manufacturer" "Panasonic"
			(at 0 0 0)
			(layer "F.Fab")
			(hide yes)
			(effects
				(font
					(size 1 1)
					(thickness 0.15)
				)
			)
		)
		(property "Tolerance" ""
			(at 0 0 0)
			(layer "F.Fab")
			(hide yes)
			(effects
				(font
					(size 1 1)
					(thickness 0.15)
				)
			)
		)
		(property "Val" "0R"
			(at 0 0 0)
			(layer "F.Fab")
			(hide yes)
			(effects
				(font
					(size 1 1)
					(thickness 0.15)
				)
			)
		)
		(sheetname "Power supply")
		(sheetfile "power_supply.kicad_sch")
		(attr smd exclude_from_pos_files exclude_from_bom dnp)
		(fp_rect
			(start -0.93 -0.47)
			(end 0.93 0.47)
			(stroke
				(width 0.05)
				(type solid)
			)
			(fill no)
			(layer "F.CrtYd")
		)
		(fp_rect
			(start -0.5 -0.25)
			(end 0.5 0.25)
			(stroke
				(width 0.15)
				(type solid)
			)
			(fill no)
			(layer "F.Fab")
		)
		(pad "1" smd roundrect
			(at -0.485 0)
			(size 0.59 0.64)
			(layers "F.Cu" "F.Mask" "F.Paste")
			(roundrect_rratio 0.25)
			(net 20 "/Power supply/PWR_EN")
			(pintype "passive")
		)
		(pad "2" smd roundrect
			(at 0.485 0)
			(size 0.59 0.64)
			(layers "F.Cu" "F.Mask" "F.Paste")
			(roundrect_rratio 0.25)
			(net 61 "Net-(R29-Pad2)")
			(pintype "passive")
		)
	)
	(footprint "antmicro-footprints:TP_SMD_0.75mm"
		(layer "F.Cu")
		(at 102.4 71)
		(property "Reference" "TP7"
			(at -2.3 5.6 0)
			(unlocked yes)
			(layer "F.SilkS")
			(effects
				(font
					(size 0.7 0.7)
					(thickness 0.15)
				)
				(justify left bottom)
			)
		)
		(property "Value" "TP_0.75mm_SMD"
			(at 0 1.2 0)
			(layer "F.Fab")
			(effects
				(font
					(size 0.7 0.7)
					(thickness 0.15)
				)
				(justify left bottom)
			)
		)
		(property "Author" "Antmicro"
			(at 0 0 0)
			(layer "F.Fab")
			(hide yes)
			(effects
				(font
					(size 1 1)
					(thickness 0.15)
				)
			)
		)
		(property "License" "Apache-2.0"
			(at 0 0 0)
			(layer "F.Fab")
			(hide yes)
			(effects
				(font
					(size 1 1)
					(thickness 0.15)
				)
			)
		)
		(property "MPN" ""
			(at 0 0 0)
			(layer "F.Fab")
			(hide yes)
			(effects
				(font
					(size 1 1)
					(thickness 0.15)
				)
			)
		)
		(property "Manufacturer" ""
			(at 0 0 0)
			(layer "F.Fab")
			(hide yes)
			(effects
				(font
					(size 1 1)
					(thickness 0.15)
				)
			)
		)
		(sheetname "Power supply")
		(sheetfile "power_supply.kicad_sch")
		(attr exclude_from_pos_files)
		(pad "1" smd circle
			(at 0 0)
			(size 0.75 0.75)
			(layers "F.Cu" "F.Mask")
			(net 10 "/Power supply/VOUT4")
			(pinfunction "1")
			(pintype "passive")
		)
	)
	(footprint "antmicro-footprints:R_Array_4x0402_Panasonic_EXB28V"
		(layer "F.Cu")
		(at 166.2 93.8)
		(property "Reference" "R57"
			(at -1.301 -1.45 0)
			(unlocked yes)
			(layer "F.SilkS")
			(effects
				(font
					(size 0.7 0.7)
					(thickness 0.15)
				)
				(justify left bottom)
			)
		)
		(property "Value" "R_4x100R_0402_array"
			(at -1.5 2 0)
			(layer "F.Fab")
			(effects
				(font
					(size 0.7 0.7)
					(thickness 0.15)
				)
				(justify left bottom)
			)
		)
		(property "Author" "Antmicro"
			(at 0 0 0)
			(layer "F.Fab")
			(hide yes)
			(effects
				(font
					(size 1 1)
					(thickness 0.15)
				)
			)
		)
		(property "License" "Apache-2.0"
			(at 0 0 0)
			(layer "F.Fab")
			(hide yes)
			(effects
				(font
					(size 1 1)
					(thickness 0.15)
				)
			)
		)
		(property "MPN" "EXB-28V101JX"
			(at 0 0 0)
			(layer "F.Fab")
			(hide yes)
			(effects
				(font
					(size 1 1)
					(thickness 0.15)
				)
			)
		)
		(property "Manufacturer" "Panasonic"
			(at 0 0 0)
			(layer "F.Fab")
			(hide yes)
			(effects
				(font
					(size 1 1)
					(thickness 0.15)
				)
			)
		)
		(property "Val" "R_4x100R_0402"
			(at 0 0 0)
			(layer "F.Fab")
			(hide yes)
			(effects
				(font
					(size 1 1)
					(thickness 0.15)
				)
			)
		)
		(sheetname "Translators1")
		(sheetfile "translators.kicad_sch")
		(attr smd)
		(fp_line
			(start -1.25 -0.5)
			(end -1.25 0.498)
			(stroke
				(width 0.15)
				(type solid)
			)
			(layer "F.SilkS")
		)
		(fp_line
			(start 1.25 0.499)
			(end 1.25 -0.499)
			(stroke
				(width 0.15)
				(type solid)
			)
			(layer "F.SilkS")
		)
		(fp_rect
			(start -1.25 -0.8)
			(end 1.25 0.8)
			(stroke
				(width 0.05)
				(type solid)
			)
			(fill no)
			(layer "F.CrtYd")
		)
		(fp_line
			(start -1 -0.5)
			(end 0.998 -0.5)
			(stroke
				(width 0.15)
				(type solid)
			)
			(layer "F.Fab")
		)
		(fp_line
			(start -1 0.498)
			(end -1 -0.5)
			(stroke
				(width 0.15)
				(type solid)
			)
			(layer "F.Fab")
		)
		(fp_line
			(start 0.998 -0.5)
			(end 0.998 0.498)
			(stroke
				(width 0.15)
				(type solid)
			)
			(layer "F.Fab")
		)
		(fp_line
			(start 0.998 0.498)
			(end -1 0.498)
			(stroke
				(width 0.15)
				(type solid)
			)
			(layer "F.Fab")
		)
		(pad "1" smd roundrect
			(at -0.8875 0.45)
			(size 0.525 0.5)
			(layers "F.Cu" "F.Mask" "F.Paste")
			(roundrect_rratio 0.25)
			(net 125 "/SODIMM/LPDDR5_IN_B.DQ3")
			(pinfunction "R1.1")
			(pintype "passive")
		)
		(pad "2" smd roundrect
			(at -0.25 0.45)
			(size 0.25 0.5)
			(layers "F.Cu" "F.Mask" "F.Paste")
			(roundrect_rratio 0.25)
			(net 123 "/SODIMM/LPDDR5_IN_B.DQ1")
			(pinfunction "R2.1")
			(pintype "passive")
		)
		(pad "3" smd roundrect
			(at 0.25 0.45)
			(size 0.25 0.5)
			(layers "F.Cu" "F.Mask" "F.Paste")
			(roundrect_rratio 0.25)
			(net 124 "/SODIMM/LPDDR5_IN_B.DQ2")
			(pinfunction "R3.1")
			(pintype "passive")
		)
		(pad "4" smd roundrect
			(at 0.8875 0.45)
			(size 0.525 0.5)
			(layers "F.Cu" "F.Mask" "F.Paste")
			(roundrect_rratio 0.25)
			(net 122 "/SODIMM/LPDDR5_IN_B.DQ0")
			(pinfunction "R4.1")
			(pintype "passive")
		)
		(pad "5" smd roundrect
			(at 0.8875 -0.45)
			(size 0.525 0.5)
			(layers "F.Cu" "F.Mask" "F.Paste")
			(roundrect_rratio 0.25)
			(net 227 "/LPDDR5/LPDDR5_B.DQ0")
			(pinfunction "R4.2")
			(pintype "passive")
		)
		(pad "6" smd roundrect
			(at 0.25 -0.45)
			(size 0.25 0.5)
			(layers "F.Cu" "F.Mask" "F.Paste")
			(roundrect_rratio 0.25)
			(net 225 "/LPDDR5/LPDDR5_B.DQ2")
			(pinfunction "R3.2")
			(pintype "passive")
		)
		(pad "7" smd roundrect
			(at -0.25 -0.45)
			(size 0.25 0.5)
			(layers "F.Cu" "F.Mask" "F.Paste")
			(roundrect_rratio 0.25)
			(net 226 "/LPDDR5/LPDDR5_B.DQ1")
			(pinfunction "R2.2")
			(pintype "passive")
		)
		(pad "8" smd roundrect
			(at -0.8875 -0.45)
			(size 0.525 0.5)
			(layers "F.Cu" "F.Mask" "F.Paste")
			(roundrect_rratio 0.25)
			(net 224 "/LPDDR5/LPDDR5_B.DQ3")
			(pinfunction "R1.2")
			(pintype "passive")
		)
	)
	(footprint "antmicro-footprints:R_0402_1005Metric"
		(layer "F.Cu")
		(at 164.075 65.35 180)
		(descr "Resistor SMD 0402")
		(tags "resistor SMD 0402")
		(property "Reference" "R31"
			(at 4.975 -0.65 0)
			(unlocked yes)
			(layer "F.SilkS")
			(effects
				(font
					(size 0.7 0.7)
					(thickness 0.15)
				)
				(justify right bottom)
			)
		)
		(property "Value" "R_25k5_0402"
			(at -1.011843 1.772047 0)
			(layer "F.Fab")
			(effects
				(font
					(size 0.7 0.7)
					(thickness 0.15)
				)
				(justify right bottom)
			)
		)
		(property "Author" "Antmicro"
			(at 328.15 130.7 0)
			(layer "F.Fab")
			(hide yes)
			(effects
				(font
					(size 1 1)
					(thickness 0.15)
				)
			)
		)
		(property "License" "Apache-2.0"
			(at 328.15 130.7 0)
			(layer "F.Fab")
			(hide yes)
			(effects
				(font
					(size 1 1)
					(thickness 0.15)
				)
			)
		)
		(property "MPN" "CR0402-FX-2552GLF"
			(at 328.15 130.7 0)
			(layer "F.Fab")
			(hide yes)
			(effects
				(font
					(size 1 1)
					(thickness 0.15)
				)
			)
		)
		(property "Manufacturer" "Bourns"
			(at 328.15 130.7 0)
			(layer "F.Fab")
			(hide yes)
			(effects
				(font
					(size 1 1)
					(thickness 0.15)
				)
			)
		)
		(property "Tolerance" "1%"
			(at 328.15 130.7 0)
			(layer "F.Fab")
			(hide yes)
			(effects
				(font
					(size 1 1)
					(thickness 0.15)
				)
			)
		)
		(property "Val" "25k5"
			(at 328.15 130.7 0)
			(layer "F.Fab")
			(hide yes)
			(effects
				(font
					(size 1 1)
					(thickness 0.15)
				)
			)
		)
		(sheetname "Power supply")
		(sheetfile "power_supply.kicad_sch")
		(attr smd)
		(fp_rect
			(start -0.93 -0.47)
			(end 0.93 0.47)
			(stroke
				(width 0.05)
				(type solid)
			)
			(fill no)
			(layer "F.CrtYd")
		)
		(fp_rect
			(start -0.5 -0.25)
			(end 0.5 0.25)
			(stroke
				(width 0.15)
				(type solid)
			)
			(fill no)
			(layer "F.Fab")
		)
		(pad "1" smd roundrect
			(at -0.485 0 180)
			(size 0.59 0.64)
			(layers "F.Cu" "F.Mask" "F.Paste")
			(roundrect_rratio 0.25)
			(net 61 "Net-(R29-Pad2)")
			(pintype "passive")
		)
		(pad "2" smd roundrect
			(at 0.485 0 180)
			(size 0.59 0.64)
			(layers "F.Cu" "F.Mask" "F.Paste")
			(roundrect_rratio 0.25)
			(net 1 "+1V1")
			(pintype "passive")
		)
	)
	(footprint "antmicro-footprints:R_0402_1005Metric"
		(layer "F.Cu")
		(at 153.95 93.8 90)
		(descr "Resistor SMD 0402")
		(tags "resistor SMD 0402")
		(property "Reference" "R88"
			(at -1.8 -1.15 0)
			(unlocked yes)
			(layer "F.SilkS")
			(effects
				(font
					(size 0.7 0.7)
					(thickness 0.15)
				)
				(justify left bottom)
			)
		)
		(property "Value" "R_100R_0402"
			(at -1.011843 1.772047 90)
			(layer "F.Fab")
			(effects
				(font
					(size 0.7 0.7)
					(thickness 0.15)
				)
				(justify left bottom)
			)
		)
		(property "Author" "Antmicro"
			(at 247.75 -60.15 0)
			(layer "F.Fab")
			(hide yes)
			(effects
				(font
					(size 1 1)
					(thickness 0.15)
				)
			)
		)
		(property "License" "Apache-2.0"
			(at 247.75 -60.15 0)
			(layer "F.Fab")
			(hide yes)
			(effects
				(font
					(size 1 1)
					(thickness 0.15)
				)
			)
		)
		(property "MPN" "CR0402-FX-1000GLF"
			(at 247.75 -60.15 0)
			(layer "F.Fab")
			(hide yes)
			(effects
				(font
					(size 1 1)
					(thickness 0.15)
				)
			)
		)
		(property "Manufacturer" "Bourns"
			(at 247.75 -60.15 0)
			(layer "F.Fab")
			(hide yes)
			(effects
				(font
					(size 1 1)
					(thickness 0.15)
				)
			)
		)
		(property "Tolerance" "1%"
			(at 247.75 -60.15 0)
			(layer "F.Fab")
			(hide yes)
			(effects
				(font
					(size 1 1)
					(thickness 0.15)
				)
			)
		)
		(property "Val" "100R"
			(at 247.75 -60.15 0)
			(layer "F.Fab")
			(hide yes)
			(effects
				(font
					(size 1 1)
					(thickness 0.15)
				)
			)
		)
		(sheetname "Translators1")
		(sheetfile "translators.kicad_sch")
		(attr smd)
		(fp_rect
			(start -0.93 -0.47)
			(end 0.93 0.47)
			(stroke
				(width 0.05)
				(type solid)
			)
			(fill no)
			(layer "F.CrtYd")
		)
		(fp_rect
			(start -0.5 -0.25)
			(end 0.5 0.25)
			(stroke
				(width 0.15)
				(type solid)
			)
			(fill no)
			(layer "F.Fab")
		)
		(pad "1" smd roundrect
			(at -0.485 0 90)
			(size 0.59 0.64)
			(layers "F.Cu" "F.Mask" "F.Paste")
			(roundrect_rratio 0.25)
			(net 121 "/SODIMM/LPDDR5_IN_B.DMI1")
			(pintype "passive")
		)
		(pad "2" smd roundrect
			(at 0.485 0 90)
			(size 0.59 0.64)
			(layers "F.Cu" "F.Mask" "F.Paste")
			(roundrect_rratio 0.25)
			(net 223 "/LPDDR5/LPDDR5_B.DMI1")
			(pintype "passive")
		)
	)
	(footprint "antmicro-footprints:SOT-523"
		(layer "F.Cu")
		(at 168.175 64.75)
		(property "Reference" "Q2"
			(at -1.375 9.35 0)
			(unlocked yes)
			(layer "F.SilkS")
			(effects
				(font
					(size 0.7 0.7)
					(thickness 0.15)
				)
				(justify left bottom)
			)
		)
		(property "Value" "DMG1012T-7"
			(at 0.1 1.824 0)
			(layer "F.Fab")
			(effects
				(font
					(size 0.7 0.7)
					(thickness 0.15)
				)
				(justify left bottom)
			)
		)
		(property "Author" "Antmicro"
			(at 0 0 0)
			(layer "F.Fab")
			(hide yes)
			(effects
				(font
					(size 1 1)
					(thickness 0.15)
				)
			)
		)
		(property "License" "Apache-2.0"
			(at 0 0 0)
			(layer "F.Fab")
			(hide yes)
			(effects
				(font
					(size 1 1)
					(thickness 0.15)
				)
			)
		)
		(property "MPN" "DMG1012T-7"
			(at 0 0 0)
			(layer "F.Fab")
			(hide yes)
			(effects
				(font
					(size 1 1)
					(thickness 0.15)
				)
			)
		)
		(property "Manufacturer" "Diodes Incorporated"
			(at 0 0 0)
			(layer "F.Fab")
			(hide yes)
			(effects
				(font
					(size 1 1)
					(thickness 0.15)
				)
			)
		)
		(sheetname "Power supply")
		(sheetfile "power_supply.kicad_sch")
		(attr smd)
		(fp_line
			(start -0.927 -0.351)
			(end -0.725 -0.551)
			(stroke
				(width 0.15)
				(type solid)
			)
			(layer "F.SilkS")
		)
		(fp_line
			(start -0.927 -0.051)
			(end -0.927 -0.351)
			(stroke
				(width 0.15)
				(type solid)
			)
			(layer "F.SilkS")
		)
		(fp_line
			(start -0.725 -0.551)
			(end -0.277 -0.551)
			(stroke
				(width 0.15)
				(type solid)
			)
			(layer "F.SilkS")
		)
		(fp_line
			(start -0.277 -0.551)
			(end -0.277 -0.75)
			(stroke
				(width 0.15)
				(type solid)
			)
			(layer "F.SilkS")
		)
		(fp_circle
			(center -0.9652 0.9652)
			(end -0.9152 0.9652)
			(stroke
				(width 0.15)
				(type solid)
			)
			(fill yes)
			(layer "F.SilkS")
		)
		(fp_line
			(start -1.12 -1.16)
			(end -1.12 1.15)
			(stroke
				(width 0.05)
				(type solid)
			)
			(layer "F.CrtYd")
		)
		(fp_line
			(start -1.12 -1.16)
			(end 1.1 -1.16)
			(stroke
				(width 0.05)
				(type solid)
			)
			(layer "F.CrtYd")
		)
		(fp_line
			(start -1.12 1.15)
			(end 1.1 1.15)
			(stroke
				(width 0.05)
				(type solid)
			)
			(layer "F.CrtYd")
		)
		(fp_line
			(start 1.1 -1.16)
			(end 1.1 1.15)
			(stroke
				(width 0.05)
				(type solid)
			)
			(layer "F.CrtYd")
		)
		(fp_line
			(start -0.802 -0.276)
			(end -0.802 0.424)
			(stroke
				(width 0.15)
				(type solid)
			)
			(layer "F.Fab")
		)
		(fp_line
			(start -0.652 -0.425)
			(end -0.802 -0.276)
			(stroke
				(width 0.15)
				(type solid)
			)
			(layer "F.Fab")
		)
		(fp_line
			(start 0.8 -0.425)
			(end -0.652 -0.425)
			(stroke
				(width 0.15)
				(type solid)
			)
			(layer "F.Fab")
		)
		(fp_line
			(start 0.8 -0.425)
			(end 0.8 0.424)
			(stroke
				(width 0.15)
				(type solid)
			)
			(layer "F.Fab")
		)
		(fp_line
			(start 0.8 0.424)
			(end -0.802 0.424)
			(stroke
				(width 0.15)
				(type solid)
			)
			(layer "F.Fab")
		)
		(fp_circle
			(center -0.9652 0.9652)
			(end -0.9144 0.9652)
			(stroke
				(width 0.15)
				(type solid)
			)
			(fill no)
			(layer "F.Fab")
		)
		(pad "1" smd rect
			(at -0.5 0.65)
			(size 0.4 0.51)
			(layers "F.Cu" "F.Mask" "F.Paste")
			(net 41 "/Power supply/PWRGD")
			(pinfunction "G")
			(pintype "bidirectional")
		)
		(pad "2" smd rect
			(at 0.498 0.65)
			(size 0.4 0.51)
			(layers "F.Cu" "F.Mask" "F.Paste")
			(net 14 "GND")
			(pinfunction "S")
			(pintype "bidirectional")
		)
		(pad "3" smd rect
			(at 0 -0.652)
			(size 0.4 0.51)
			(layers "F.Cu" "F.Mask" "F.Paste")
			(net 17 "Net-(D2-Pad2)")
			(pinfunction "D")
			(pintype "bidirectional")
		)
	)
)
